(kicad_pcb
	(version 20260206)
	(generator "pcbnew")
	(generator_version "10.0")
	(general
		(thickness 1.6)
		(legacy_teardrops no)
	)
	(paper "A4")
	(title_block
		(title "01162023_DA0F0TEBIF0_F0T_Expander_BD_F_brd_V02_OCP.brd")
		(comment 1 "Grand Teton / footprint 6602 of 9728 (PEX1), pads 356-474 of 2397")
	)
	(layers
		(0 "F.Cu" signal "TOP")
		(4 "In1.Cu" signal "GND")
		(6 "In2.Cu" signal "VCC")
		(8 "In3.Cu" signal "VCC1")
		(10 "In4.Cu" signal "GND1")
		(12 "In5.Cu" signal "IN1")
		(14 "In6.Cu" signal "GND2")
		(16 "In7.Cu" signal "IN2")
		(18 "In8.Cu" signal "GND3")
		(20 "In9.Cu" signal "IN3")
		(22 "In10.Cu" signal "GND4")
		(24 "In11.Cu" signal "IN4")
		(26 "In12.Cu" signal "GND5")
		(28 "In13.Cu" signal "IN5")
		(30 "In14.Cu" signal "GND6")
		(32 "In15.Cu" signal "IN6")
		(34 "In16.Cu" signal "GND7")
		(2 "B.Cu" signal "BOTTOM")
		(9 "F.Adhes" user "F.Adhesive")
		(11 "B.Adhes" user "B.Adhesive")
		(13 "F.Paste" user "Package Geometry/Pastemask Top")
		(15 "B.Paste" user "Package Geometry/Pastemask Bottom")
		(5 "F.SilkS" user "Ref Des/Silkscreen Top")
		(7 "B.SilkS" user "Ref Des/Silkscreen Bottom")
		(1 "F.Mask" user "Board Geometry/Soldermask Top")
		(3 "B.Mask" user "Board Geometry/Soldermask Bottom")
		(17 "Dwgs.User" user "User.Drawings")
		(19 "Cmts.User" user "User.Comments")
		(21 "Eco1.User" user "User.Eco1")
		(23 "Eco2.User" user "User.Eco2")
		(25 "Edge.Cuts" user "Board Geometry/Outline")
		(27 "Margin" user)
		(31 "F.CrtYd" user "Package Geometry/Place Bound Top")
		(29 "B.CrtYd" user "Package Geometry/Place Bound Bottom")
		(35 "F.Fab" user "Ref Des/Assembly Top")
		(33 "B.Fab" user "Ref Des/Assembly Bottom")
	)
	(footprint ""
		(layer "F.Cu")
		(at 175.749966 -295.89984)
		(property "Reference" "PEX1"
			(at -3.353562 35.593274 0)
			(unlocked yes)
			(layer "F.SilkS")
			(effects
				(font
					(size 2.032 1.524)
					(thickness 0.1524)
				)
				(justify left)
			)
		)
		(property "Value" ""
			(at 0 0 0)
			(layer "F.Fab")
			(effects
				(font
					(size 1.27 1.27)
				)
			)
		)
		(duplicate_pad_numbers_are_jumpers no)
		(pad "AG15" smd circle
			(at -9.500108 1.89992)
			(size 0.4572 0.4572)
			(layers "F.Cu" "F.Mask" "F.Paste")
			(net "P0V8_PEX1")
		)
		(pad "AG16" smd circle
			(at -8.549894 1.89992)
			(size 0.4572 0.4572)
			(layers "F.Cu" "F.Mask" "F.Paste")
			(net "GND")
		)
		(pad "AG17" smd circle
			(at -7.599934 1.89992)
			(size 0.4572 0.4572)
			(layers "F.Cu" "F.Mask" "F.Paste")
			(net "P0V8_PEX1")
		)
		(pad "AG18" smd circle
			(at -6.649974 1.89992)
			(size 0.4572 0.4572)
			(layers "F.Cu" "F.Mask" "F.Paste")
			(net "GND")
		)
		(pad "AG19" smd circle
			(at -5.700014 1.89992)
			(size 0.4572 0.4572)
			(layers "F.Cu" "F.Mask" "F.Paste")
			(net "P0V8_PEX1")
		)
		(pad "AG20" smd circle
			(at -4.750054 1.89992)
			(size 0.4572 0.4572)
			(layers "F.Cu" "F.Mask" "F.Paste")
			(net "GND")
		)
		(pad "AG21" smd circle
			(at -3.800094 1.89992)
			(size 0.4572 0.4572)
			(layers "F.Cu" "F.Mask" "F.Paste")
			(net "P0V8_PEX1")
		)
		(pad "AG22" smd circle
			(at -2.84988 1.89992)
			(size 0.4572 0.4572)
			(layers "F.Cu" "F.Mask" "F.Paste")
			(net "GND")
		)
		(pad "AG23" smd circle
			(at -1.89992 1.89992)
			(size 0.4572 0.4572)
			(layers "F.Cu" "F.Mask" "F.Paste")
			(net "P0V8_PEX1")
		)
		(pad "AG24" smd circle
			(at -0.94996 1.89992)
			(size 0.4572 0.4572)
			(layers "F.Cu" "F.Mask" "F.Paste")
			(net "GND")
		)
		(pad "AG25" smd circle
			(at 0 1.89992)
			(size 0.4572 0.4572)
			(layers "F.Cu" "F.Mask" "F.Paste")
			(net "P0V8_PEX1")
		)
		(pad "AG26" smd circle
			(at 0.94996 1.89992)
			(size 0.4572 0.4572)
			(layers "F.Cu" "F.Mask" "F.Paste")
			(net "GND")
		)
		(pad "AG27" smd circle
			(at 1.89992 1.89992)
			(size 0.4572 0.4572)
			(layers "F.Cu" "F.Mask" "F.Paste")
			(net "P0V8_PEX1")
		)
		(pad "AG28" smd circle
			(at 2.84988 1.89992)
			(size 0.4572 0.4572)
			(layers "F.Cu" "F.Mask" "F.Paste")
			(net "GND")
		)
		(pad "AG29" smd circle
			(at 3.800094 1.89992)
			(size 0.4572 0.4572)
			(layers "F.Cu" "F.Mask" "F.Paste")
			(net "P0V8_PEX1")
		)
		(pad "AG30" smd circle
			(at 4.750054 1.89992)
			(size 0.4572 0.4572)
			(layers "F.Cu" "F.Mask" "F.Paste")
			(net "GND")
		)
		(pad "AG31" smd circle
			(at 5.700014 1.89992)
			(size 0.4572 0.4572)
			(layers "F.Cu" "F.Mask" "F.Paste")
			(net "P0V8_PEX1")
		)
		(pad "AG32" smd circle
			(at 6.649974 1.89992)
			(size 0.4572 0.4572)
			(layers "F.Cu" "F.Mask" "F.Paste")
			(net "GND")
		)
		(pad "AG33" smd circle
			(at 7.599934 1.89992)
			(size 0.4572 0.4572)
			(layers "F.Cu" "F.Mask" "F.Paste")
			(net "P0V8_PEX1")
		)
		(pad "AG34" smd circle
			(at 8.549894 1.89992)
			(size 0.4572 0.4572)
			(layers "F.Cu" "F.Mask" "F.Paste")
			(net "GND")
		)
		(pad "AG35" smd circle
			(at 9.500108 1.89992)
			(size 0.4572 0.4572)
			(layers "F.Cu" "F.Mask" "F.Paste")
			(net "GND")
		)
		(pad "AG36" smd circle
			(at 10.450068 1.89992)
			(size 0.4572 0.4572)
			(layers "F.Cu" "F.Mask" "F.Paste")
			(net "P1V25_PEX1")
		)
		(pad "AG37" smd circle
			(at 11.400028 1.89992)
			(size 0.4572 0.4572)
			(layers "F.Cu" "F.Mask" "F.Paste")
			(net "GND")
		)
		(pad "AG38" smd circle
			(at 12.349988 1.89992)
			(size 0.4572 0.4572)
			(layers "F.Cu" "F.Mask" "F.Paste")
			(net "P1V25_SERDES_VDDPLL_PEX1")
		)
		(pad "AG39" smd circle
			(at 13.299948 1.89992)
			(size 0.4572 0.4572)
			(layers "F.Cu" "F.Mask" "F.Paste")
			(net "GND")
		)
		(pad "AG40" smd circle
			(at 14.249908 1.89992)
			(size 0.4572 0.4572)
			(layers "F.Cu" "F.Mask" "F.Paste")
			(net "GND")
		)
		(pad "AG41" smd circle
			(at 15.200122 1.89992)
			(size 0.4572 0.4572)
			(layers "F.Cu" "F.Mask" "F.Paste")
			(net "GND")
		)
		(pad "AG42" smd circle
			(at 16.150082 1.89992)
			(size 0.4572 0.4572)
			(layers "F.Cu" "F.Mask" "F.Paste")
			(net "GND")
		)
		(pad "AG43" smd circle
			(at 17.100042 1.89992)
			(size 0.4572 0.4572)
			(layers "F.Cu" "F.Mask" "F.Paste")
			(net "Net_1360")
		)
		(pad "AG44" smd circle
			(at 18.050002 1.89992)
			(size 0.4572 0.4572)
			(layers "F.Cu" "F.Mask" "F.Paste")
			(net "Net_1433")
		)
		(pad "AG45" smd circle
			(at 18.999962 1.89992)
			(size 0.4572 0.4572)
			(layers "F.Cu" "F.Mask" "F.Paste")
			(net "GND")
		)
		(pad "AG46" smd circle
			(at 19.949922 1.89992)
			(size 0.4572 0.4572)
			(layers "F.Cu" "F.Mask" "F.Paste")
			(net "Net_1557")
		)
		(pad "AG47" smd circle
			(at 20.899882 1.89992)
			(size 0.4572 0.4572)
			(layers "F.Cu" "F.Mask" "F.Paste")
			(net "Net_1603")
		)
		(pad "AG48" smd circle
			(at 21.850096 1.89992)
			(size 0.4572 0.4572)
			(layers "F.Cu" "F.Mask" "F.Paste")
			(net "GND")
		)
		(pad "AG49" smd circle
			(at 22.800056 1.89992)
			(size 0.4572 0.4572)
			(layers "F.Cu" "F.Mask" "F.Paste")
			(net "GND")
		)
		(pad "AH1" smd circle
			(at -22.800056 2.84988)
			(size 0.4572 0.4572)
			(layers "F.Cu" "F.Mask" "F.Paste")
			(net "GND")
		)
		(pad "AH2" smd circle
			(at -21.850096 2.84988)
			(size 0.4572 0.4572)
			(layers "F.Cu" "F.Mask" "F.Paste")
			(net "GND")
		)
		(pad "AH3" smd circle
			(at -20.899882 2.84988)
			(size 0.4572 0.4572)
			(layers "F.Cu" "F.Mask" "F.Paste")
			(net "GND")
		)
		(pad "AH4" smd circle
			(at -19.949922 2.84988)
			(size 0.4572 0.4572)
			(layers "F.Cu" "F.Mask" "F.Paste")
			(net "Net_5229")
		)
		(pad "AH5" smd circle
			(at -18.999962 2.84988)
			(size 0.4572 0.4572)
			(layers "F.Cu" "F.Mask" "F.Paste")
			(net "Net_5230")
		)
		(pad "AH6" smd circle
			(at -18.050002 2.84988)
			(size 0.4572 0.4572)
			(layers "F.Cu" "F.Mask" "F.Paste")
			(net "GND")
		)
		(pad "AH7" smd circle
			(at -17.100042 2.84988)
			(size 0.4572 0.4572)
			(layers "F.Cu" "F.Mask" "F.Paste")
			(net "SPI_PEX1_CLK")
		)
		(pad "AH8" smd circle
			(at -16.150082 2.84988)
			(size 0.4572 0.4572)
			(layers "F.Cu" "F.Mask" "F.Paste")
			(net "SPI_PEX1_SDIO3")
		)
		(pad "AH9" smd circle
			(at -15.200122 2.84988)
			(size 0.4572 0.4572)
			(layers "F.Cu" "F.Mask" "F.Paste")
			(net "GND")
		)
		(pad "AH10" smd circle
			(at -14.249908 2.84988)
			(size 0.4572 0.4572)
			(layers "F.Cu" "F.Mask" "F.Paste")
			(net "P1V8_PEX")
		)
		(pad "AH11" smd circle
			(at -13.299948 2.84988)
			(size 0.4572 0.4572)
			(layers "F.Cu" "F.Mask" "F.Paste")
			(net "GND")
		)
		(pad "AH12" smd circle
			(at -12.349988 2.84988)
			(size 0.4572 0.4572)
			(layers "F.Cu" "F.Mask" "F.Paste")
			(net "PCEPLL6_VDDA18_PEX1")
		)
		(pad "AH13" smd circle
			(at -11.400028 2.84988)
			(size 0.4572 0.4572)
			(layers "F.Cu" "F.Mask" "F.Paste")
			(net "GND")
		)
		(pad "AH14" smd circle
			(at -10.450068 2.84988)
			(size 0.4572 0.4572)
			(layers "F.Cu" "F.Mask" "F.Paste")
			(net "P0V8_PEX1")
		)
		(pad "AH15" smd circle
			(at -9.500108 2.84988)
			(size 0.4572 0.4572)
			(layers "F.Cu" "F.Mask" "F.Paste")
			(net "GND")
		)
		(pad "AH16" smd circle
			(at -8.549894 2.84988)
			(size 0.4572 0.4572)
			(layers "F.Cu" "F.Mask" "F.Paste")
			(net "P0V8_SERDES_VDDA_PEX1")
		)
		(pad "AH17" smd circle
			(at -7.599934 2.84988)
			(size 0.4572 0.4572)
			(layers "F.Cu" "F.Mask" "F.Paste")
			(net "P0V8_SERDES_VDDA_PEX1")
		)
		(pad "AH18" smd circle
			(at -6.649974 2.84988)
			(size 0.4572 0.4572)
			(layers "F.Cu" "F.Mask" "F.Paste")
			(net "P0V8_SERDES_VDDA_PEX1")
		)
		(pad "AH19" smd circle
			(at -5.700014 2.84988)
			(size 0.4572 0.4572)
			(layers "F.Cu" "F.Mask" "F.Paste")
			(net "P0V8_SERDES_VDDA_PEX1")
		)
		(pad "AH20" smd circle
			(at -4.750054 2.84988)
			(size 0.4572 0.4572)
			(layers "F.Cu" "F.Mask" "F.Paste")
			(net "P0V8_SERDES_VDDA_PEX1")
		)
		(pad "AH21" smd circle
			(at -3.800094 2.84988)
			(size 0.4572 0.4572)
			(layers "F.Cu" "F.Mask" "F.Paste")
			(net "P0V8_SERDES_VDDA_PEX1")
		)
		(pad "AH22" smd circle
			(at -2.84988 2.84988)
			(size 0.4572 0.4572)
			(layers "F.Cu" "F.Mask" "F.Paste")
			(net "P0V8_SERDES_VDDA_PEX1")
		)
		(pad "AH23" smd circle
			(at -1.89992 2.84988)
			(size 0.4572 0.4572)
			(layers "F.Cu" "F.Mask" "F.Paste")
			(net "P0V8_SERDES_VDDA_PEX1")
		)
		(pad "AH24" smd circle
			(at -0.94996 2.84988)
			(size 0.4572 0.4572)
			(layers "F.Cu" "F.Mask" "F.Paste")
			(net "P0V8_SERDES_VDDA_PEX1")
		)
		(pad "AH25" smd circle
			(at 0 2.84988)
			(size 0.4572 0.4572)
			(layers "F.Cu" "F.Mask" "F.Paste")
			(net "P0V8_SERDES_VDDA_PEX1")
		)
		(pad "AH26" smd circle
			(at 0.94996 2.84988)
			(size 0.4572 0.4572)
			(layers "F.Cu" "F.Mask" "F.Paste")
			(net "P0V8_SERDES_VDDA_PEX1")
		)
		(pad "AH27" smd circle
			(at 1.89992 2.84988)
			(size 0.4572 0.4572)
			(layers "F.Cu" "F.Mask" "F.Paste")
			(net "P0V8_SERDES_VDDA_PEX1")
		)
		(pad "AH28" smd circle
			(at 2.84988 2.84988)
			(size 0.4572 0.4572)
			(layers "F.Cu" "F.Mask" "F.Paste")
			(net "P0V8_SERDES_VDDA_PEX1")
		)
		(pad "AH29" smd circle
			(at 3.800094 2.84988)
			(size 0.4572 0.4572)
			(layers "F.Cu" "F.Mask" "F.Paste")
			(net "P0V8_SERDES_VDDA_PEX1")
		)
		(pad "AH30" smd circle
			(at 4.750054 2.84988)
			(size 0.4572 0.4572)
			(layers "F.Cu" "F.Mask" "F.Paste")
			(net "P0V8_SERDES_VDDA_PEX1")
		)
		(pad "AH31" smd circle
			(at 5.700014 2.84988)
			(size 0.4572 0.4572)
			(layers "F.Cu" "F.Mask" "F.Paste")
			(net "P0V8_SERDES_VDDA_PEX1")
		)
		(pad "AH32" smd circle
			(at 6.649974 2.84988)
			(size 0.4572 0.4572)
			(layers "F.Cu" "F.Mask" "F.Paste")
			(net "P0V8_SERDES_VDDA_PEX1")
		)
		(pad "AH33" smd circle
			(at 7.599934 2.84988)
			(size 0.4572 0.4572)
			(layers "F.Cu" "F.Mask" "F.Paste")
			(net "P0V8_SERDES_VDDA_PEX1")
		)
		(pad "AH34" smd circle
			(at 8.549894 2.84988)
			(size 0.4572 0.4572)
			(layers "F.Cu" "F.Mask" "F.Paste")
			(net "GND")
		)
		(pad "AH35" smd circle
			(at 9.500108 2.84988)
			(size 0.4572 0.4572)
			(layers "F.Cu" "F.Mask" "F.Paste")
			(net "GND")
		)
		(pad "AH36" smd circle
			(at 10.450068 2.84988)
			(size 0.4572 0.4572)
			(layers "F.Cu" "F.Mask" "F.Paste")
			(net "GND")
		)
		(pad "AH37" smd circle
			(at 11.400028 2.84988)
			(size 0.4572 0.4572)
			(layers "F.Cu" "F.Mask" "F.Paste")
			(net "GND")
		)
		(pad "AH38" smd circle
			(at 12.349988 2.84988)
			(size 0.4572 0.4572)
			(layers "F.Cu" "F.Mask" "F.Paste")
			(net "GND")
		)
		(pad "AH39" smd circle
			(at 13.299948 2.84988)
			(size 0.4572 0.4572)
			(layers "F.Cu" "F.Mask" "F.Paste")
			(net "GND")
		)
		(pad "AH40" smd circle
			(at 14.249908 2.84988)
			(size 0.4572 0.4572)
			(layers "F.Cu" "F.Mask" "F.Paste")
			(net "GND")
		)
		(pad "AH41" smd circle
			(at 15.200122 2.84988)
			(size 0.4572 0.4572)
			(layers "F.Cu" "F.Mask" "F.Paste")
			(net "Net_1374")
		)
		(pad "AH42" smd circle
			(at 16.150082 2.84988)
			(size 0.4572 0.4572)
			(layers "F.Cu" "F.Mask" "F.Paste")
			(net "Net_1397")
		)
		(pad "AH43" smd circle
			(at 17.100042 2.84988)
			(size 0.4572 0.4572)
			(layers "F.Cu" "F.Mask" "F.Paste")
			(net "GND")
		)
		(pad "AH44" smd circle
			(at 18.050002 2.84988)
			(size 0.4572 0.4572)
			(layers "F.Cu" "F.Mask" "F.Paste")
			(net "GND")
		)
		(pad "AH45" smd circle
			(at 18.999962 2.84988)
			(size 0.4572 0.4572)
			(layers "F.Cu" "F.Mask" "F.Paste")
			(net "GND")
		)
		(pad "AH46" smd circle
			(at 19.949922 2.84988)
			(size 0.4572 0.4572)
			(layers "F.Cu" "F.Mask" "F.Paste")
			(net "GND")
		)
		(pad "AH47" smd circle
			(at 20.899882 2.84988)
			(size 0.4572 0.4572)
			(layers "F.Cu" "F.Mask" "F.Paste")
			(net "GND")
		)
		(pad "AH48" smd circle
			(at 21.850096 2.84988)
			(size 0.4572 0.4572)
			(layers "F.Cu" "F.Mask" "F.Paste")
			(net "Net_1587")
		)
		(pad "AH49" smd circle
			(at 22.800056 2.84988)
			(size 0.4572 0.4572)
			(layers "F.Cu" "F.Mask" "F.Paste")
			(net "Net_1591")
		)
		(pad "AJ1" smd circle
			(at -22.800056 3.800094)
			(size 0.4572 0.4572)
			(layers "F.Cu" "F.Mask" "F.Paste")
			(net "Net_5232")
		)
		(pad "AJ2" smd circle
			(at -21.850096 3.800094)
			(size 0.4572 0.4572)
			(layers "F.Cu" "F.Mask" "F.Paste")
			(net "Net_5233")
		)
		(pad "AJ3" smd circle
			(at -20.899882 3.800094)
			(size 0.4572 0.4572)
			(layers "F.Cu" "F.Mask" "F.Paste")
			(net "GND")
		)
		(pad "AJ4" smd circle
			(at -19.949922 3.800094)
			(size 0.4572 0.4572)
			(layers "F.Cu" "F.Mask" "F.Paste")
			(net "GND")
		)
		(pad "AJ5" smd circle
			(at -18.999962 3.800094)
			(size 0.4572 0.4572)
			(layers "F.Cu" "F.Mask" "F.Paste")
			(net "GND")
		)
		(pad "AJ6" smd circle
			(at -18.050002 3.800094)
			(size 0.4572 0.4572)
			(layers "F.Cu" "F.Mask" "F.Paste")
			(net "GND")
		)
		(pad "AJ7" smd circle
			(at -17.100042 3.800094)
			(size 0.4572 0.4572)
			(layers "F.Cu" "F.Mask" "F.Paste")
			(net "SPI_PEX1_CS_N")
		)
		(pad "AJ8" smd circle
			(at -16.150082 3.800094)
			(size 0.4572 0.4572)
			(layers "F.Cu" "F.Mask" "F.Paste")
			(net "Net_5303")
		)
		(pad "AJ9" smd circle
			(at -15.200122 3.800094)
			(size 0.4572 0.4572)
			(layers "F.Cu" "F.Mask" "F.Paste")
			(net "GND")
		)
		(pad "AJ10" smd circle
			(at -14.249908 3.800094)
			(size 0.4572 0.4572)
			(layers "F.Cu" "F.Mask" "F.Paste")
			(net "P1V8_PEX")
		)
		(pad "AJ11" smd circle
			(at -13.299948 3.800094)
			(size 0.4572 0.4572)
			(layers "F.Cu" "F.Mask" "F.Paste")
			(net "GND")
		)
		(pad "AJ12" smd circle
			(at -12.349988 3.800094)
			(size 0.4572 0.4572)
			(layers "F.Cu" "F.Mask" "F.Paste")
			(net "GND")
		)
		(pad "AJ13" smd circle
			(at -11.400028 3.800094)
			(size 0.4572 0.4572)
			(layers "F.Cu" "F.Mask" "F.Paste")
			(net "PCEPLL7_VDDA18_PEX1")
		)
		(pad "AJ14" smd circle
			(at -10.450068 3.800094)
			(size 0.4572 0.4572)
			(layers "F.Cu" "F.Mask" "F.Paste")
			(net "GND")
		)
		(pad "AJ15" smd circle
			(at -9.500108 3.800094)
			(size 0.4572 0.4572)
			(layers "F.Cu" "F.Mask" "F.Paste")
			(net "P0V8_PEX1")
		)
		(pad "AJ16" smd circle
			(at -8.549894 3.800094)
			(size 0.4572 0.4572)
			(layers "F.Cu" "F.Mask" "F.Paste")
			(net "GND")
		)
		(pad "AJ17" smd circle
			(at -7.599934 3.800094)
			(size 0.4572 0.4572)
			(layers "F.Cu" "F.Mask" "F.Paste")
			(net "GND")
		)
		(pad "AJ18" smd circle
			(at -6.649974 3.800094)
			(size 0.4572 0.4572)
			(layers "F.Cu" "F.Mask" "F.Paste")
			(net "GND")
		)
		(pad "AJ19" smd circle
			(at -5.700014 3.800094)
			(size 0.4572 0.4572)
			(layers "F.Cu" "F.Mask" "F.Paste")
			(net "GND")
		)
		(pad "AJ20" smd circle
			(at -4.750054 3.800094)
			(size 0.4572 0.4572)
			(layers "F.Cu" "F.Mask" "F.Paste")
			(net "GND")
		)
		(pad "AJ21" smd circle
			(at -3.800094 3.800094)
			(size 0.4572 0.4572)
			(layers "F.Cu" "F.Mask" "F.Paste")
			(net "GND")
		)
		(pad "AJ22" smd circle
			(at -2.84988 3.800094)
			(size 0.4572 0.4572)
			(layers "F.Cu" "F.Mask" "F.Paste")
			(net "GND")
		)
		(pad "AJ23" smd circle
			(at -1.89992 3.800094)
			(size 0.4572 0.4572)
			(layers "F.Cu" "F.Mask" "F.Paste")
			(net "GND")
		)
		(pad "AJ24" smd circle
			(at -0.94996 3.800094)
			(size 0.4572 0.4572)
			(layers "F.Cu" "F.Mask" "F.Paste")
			(net "GND")
		)
		(pad "AJ25" smd circle
			(at 0 3.800094)
			(size 0.4572 0.4572)
			(layers "F.Cu" "F.Mask" "F.Paste")
			(net "GND")
		)
		(pad "AJ26" smd circle
			(at 0.94996 3.800094)
			(size 0.4572 0.4572)
			(layers "F.Cu" "F.Mask" "F.Paste")
			(net "GND")
		)
		(pad "AJ27" smd circle
			(at 1.89992 3.800094)
			(size 0.4572 0.4572)
			(layers "F.Cu" "F.Mask" "F.Paste")
			(net "GND")
		)
		(pad "AJ28" smd circle
			(at 2.84988 3.800094)
			(size 0.4572 0.4572)
			(layers "F.Cu" "F.Mask" "F.Paste")
			(net "GND")
		)
		(pad "AJ29" smd circle
			(at 3.800094 3.800094)
			(size 0.4572 0.4572)
			(layers "F.Cu" "F.Mask" "F.Paste")
			(net "GND")
		)
		(pad "AJ30" smd circle
			(at 4.750054 3.800094)
			(size 0.4572 0.4572)
			(layers "F.Cu" "F.Mask" "F.Paste")
			(net "GND")
		)
		(pad "AJ31" smd circle
			(at 5.700014 3.800094)
			(size 0.4572 0.4572)
			(layers "F.Cu" "F.Mask" "F.Paste")
			(net "GND")
		)
		(pad "AJ32" smd circle
			(at 6.649974 3.800094)
			(size 0.4572 0.4572)
			(layers "F.Cu" "F.Mask" "F.Paste")
			(net "GND")
		)
		(pad "AJ33" smd circle
			(at 7.599934 3.800094)
			(size 0.4572 0.4572)
			(layers "F.Cu" "F.Mask" "F.Paste")
			(net "GND")
		)
		(pad "AJ34" smd circle
			(at 8.549894 3.800094)
			(size 0.4572 0.4572)
			(layers "F.Cu" "F.Mask" "F.Paste")
			(net "GND")
		)
		(pad "AJ35" smd circle
			(at 9.500108 3.800094)
			(size 0.4572 0.4572)
			(layers "F.Cu" "F.Mask" "F.Paste")
			(net "GND")
		)
	)
)
